(kicad_pcb
	(version 20260206)
	(generator "pcbnew")
	(generator_version "10.0")
	(general
		(thickness 1.6)
		(legacy_teardrops no)
	)
	(paper "A4")
	(title_block
		(title "fcb — 12433-1M.1206WZS1330.brd")
		(comment 1 "Open Vault / Knox (Wiwynn) / footprints 417-420 of 495")
	)
	(layers
		(0 "F.Cu" signal "TOP")
		(4 "In1.Cu" signal "L2GND")
		(6 "In2.Cu" signal "L3VCC")
		(2 "B.Cu" signal "BOTTOM")
		(9 "F.Adhes" user "F.Adhesive")
		(11 "B.Adhes" user "B.Adhesive")
		(13 "F.Paste" user "Package Geometry/Pastemask Top")
		(15 "B.Paste" user "Package Geometry/Pastemask Bottom")
		(5 "F.SilkS" user "Ref Des/Silkscreen Top")
		(7 "B.SilkS" user "Ref Des/Silkscreen Bottom")
		(1 "F.Mask" user "Board Geometry/Soldermask Top")
		(3 "B.Mask" user "Board Geometry/Soldermask Bottom")
		(17 "Dwgs.User" user "User.Drawings")
		(19 "Cmts.User" user "User.Comments")
		(21 "Eco1.User" user "User.Eco1")
		(23 "Eco2.User" user "User.Eco2")
		(25 "Edge.Cuts" user "Board Geometry/Outline")
		(27 "Margin" user)
		(31 "F.CrtYd" user "Package Geometry/Place Bound Top")
		(29 "B.CrtYd" user "Package Geometry/Place Bound Bottom")
		(35 "F.Fab" user "Ref Des/Assembly Top")
		(33 "B.Fab" user "Ref Des/Assembly Bottom")
	)
	(footprint ""
		(layer "F.Cu")
		(at 45.500036 -19.99996)
		(property "Reference" "H1"
			(at 0 0 0)
			(layer "F.SilkS")
			(hide yes)
			(effects
				(font
					(size 1.27 1.27)
				)
			)
		)
		(property "Value" "HOLE315R138"
			(at 0 -7.0612 0)
			(unlocked yes)
			(layer "F.Fab")
			(hide yes)
			(effects
				(font
					(size 1.016 1.016)
					(thickness 0.1524)
				)
			)
		)
		(property "Device Type" "HOLE315R138"
			(at 0 -8.5852 0)
			(unlocked yes)
			(layer "F.Fab")
			(hide yes)
			(effects
				(font
					(size 1.016 1.016)
					(thickness 0.1524)
				)
			)
		)
		(duplicate_pad_numbers_are_jumpers no)
		(fp_poly
			(pts
				(xy 0 4.3053) (xy -0.13462 4.30276) (xy -0.27051 4.29641) (xy -0.40513 4.28625) (xy -0.53975 4.27101)
				(xy -0.6731 4.25196) (xy -0.80645 4.2291) (xy -0.9398 4.20116) (xy -1.07061 4.17068) (xy -1.20142 4.13385)
				(xy -1.33096 4.09448) (xy -1.45796 4.0513) (xy -1.58496 4.00304) (xy -1.70942 3.95097) (xy -1.83261 3.89509)
				(xy -1.95453 3.83667) (xy -2.07391 3.77317) (xy -2.19202 3.70586) (xy -2.30632 3.63474) (xy -2.41935 3.56108)
				(xy -2.53111 3.48361) (xy -2.63906 3.40233) (xy -2.74447 3.31724) (xy -2.84734 3.22961) (xy -2.94767 3.13817)
				(xy -3.04419 3.04419) (xy -3.13817 2.94767) (xy -3.22961 2.84734) (xy -3.31724 2.74447) (xy -3.40233 2.63906)
				(xy -3.48361 2.53111) (xy -3.56108 2.41935) (xy -3.63474 2.30632) (xy -3.70586 2.19202) (xy -3.77317 2.07391)
				(xy -3.83667 1.95453) (xy -3.89509 1.83261) (xy -3.95097 1.70942) (xy -4.00304 1.58496) (xy -4.0513 1.45796)
				(xy -4.09448 1.33096) (xy -4.13385 1.20142) (xy -4.17068 1.07061) (xy -4.20116 0.9398) (xy -4.2291 0.80645)
				(xy -4.25196 0.6731) (xy -4.27101 0.53975) (xy -4.28625 0.40513) (xy -4.29641 0.27051) (xy -4.30276 0.13462)
				(xy -4.3053 0) (xy -4.30276 -0.13462) (xy -4.29641 -0.27051) (xy -4.28625 -0.40513) (xy -4.27101 -0.53975)
				(xy -4.25196 -0.6731) (xy -4.2291 -0.80645) (xy -4.20116 -0.9398) (xy -4.17068 -1.07061) (xy -4.13385 -1.20142)
				(xy -4.09448 -1.33096) (xy -4.0513 -1.45796) (xy -4.00304 -1.58496) (xy -3.95097 -1.70942) (xy -3.89509 -1.83261)
				(xy -3.83667 -1.95453) (xy -3.77317 -2.07391) (xy -3.70586 -2.19202) (xy -3.63474 -2.30632) (xy -3.56108 -2.41935)
				(xy -3.48361 -2.53111) (xy -3.40233 -2.63906) (xy -3.31724 -2.74447) (xy -3.22961 -2.84734) (xy -3.13817 -2.94767)
				(xy -3.04419 -3.04419) (xy -2.94767 -3.13817) (xy -2.84734 -3.22961) (xy -2.74447 -3.31724) (xy -2.63906 -3.40233)
				(xy -2.53111 -3.48361) (xy -2.41935 -3.56108) (xy -2.30632 -3.63474) (xy -2.19202 -3.70586) (xy -2.07391 -3.77317)
				(xy -1.95453 -3.83667) (xy -1.83261 -3.89509) (xy -1.70942 -3.95097) (xy -1.58496 -4.00304) (xy -1.45796 -4.0513)
				(xy -1.33096 -4.09448) (xy -1.20142 -4.13385) (xy -1.07061 -4.17068) (xy -0.9398 -4.20116) (xy -0.80645 -4.2291)
				(xy -0.6731 -4.25196) (xy -0.53975 -4.27101) (xy -0.40513 -4.28625) (xy -0.27051 -4.29641) (xy -0.13462 -4.30276)
				(xy 0 -4.3053) (xy 0.13462 -4.30276) (xy 0.27051 -4.29641) (xy 0.40513 -4.28625) (xy 0.53975 -4.27101)
				(xy 0.6731 -4.25196) (xy 0.80645 -4.2291) (xy 0.9398 -4.20116) (xy 1.07061 -4.17068) (xy 1.20142 -4.13385)
				(xy 1.33096 -4.09448) (xy 1.45796 -4.0513) (xy 1.58496 -4.00304) (xy 1.70942 -3.95097) (xy 1.83261 -3.89509)
				(xy 1.95453 -3.83667) (xy 2.07391 -3.77317) (xy 2.19202 -3.70586) (xy 2.30632 -3.63474) (xy 2.41935 -3.56108)
				(xy 2.53111 -3.48361) (xy 2.63906 -3.40233) (xy 2.74447 -3.31724) (xy 2.84734 -3.22961) (xy 2.94767 -3.13817)
				(xy 3.04419 -3.04419) (xy 3.13817 -2.94767) (xy 3.22961 -2.84734) (xy 3.31724 -2.74447) (xy 3.40233 -2.63906)
				(xy 3.48361 -2.53111) (xy 3.56108 -2.41935) (xy 3.63474 -2.30632) (xy 3.70586 -2.19202) (xy 3.77317 -2.07391)
				(xy 3.83667 -1.95453) (xy 3.89509 -1.83261) (xy 3.95097 -1.70942) (xy 4.00304 -1.58496) (xy 4.0513 -1.45796)
				(xy 4.09448 -1.33096) (xy 4.13385 -1.20142) (xy 4.17068 -1.07061) (xy 4.20116 -0.9398) (xy 4.2291 -0.80645)
				(xy 4.25196 -0.6731) (xy 4.27101 -0.53975) (xy 4.28625 -0.40513) (xy 4.29641 -0.27051) (xy 4.30276 -0.13462)
				(xy 4.3053 0) (xy 4.30276 0.13462) (xy 4.29641 0.27051) (xy 4.28625 0.40513) (xy 4.27101 0.53975)
				(xy 4.25196 0.6731) (xy 4.2291 0.80645) (xy 4.20116 0.9398) (xy 4.17068 1.07061) (xy 4.13385 1.20142)
				(xy 4.09448 1.33096) (xy 4.0513 1.45796) (xy 4.00304 1.58496) (xy 3.95097 1.70942) (xy 3.89509 1.83261)
				(xy 3.83667 1.95453) (xy 3.77317 2.07391) (xy 3.70586 2.19202) (xy 3.63474 2.30632) (xy 3.56108 2.41935)
				(xy 3.48361 2.53111) (xy 3.40233 2.63906) (xy 3.31724 2.74447) (xy 3.22961 2.84734) (xy 3.13817 2.94767)
				(xy 3.04419 3.04419) (xy 2.94767 3.13817) (xy 2.84734 3.22961) (xy 2.74447 3.31724) (xy 2.63906 3.40233)
				(xy 2.53111 3.48361) (xy 2.41935 3.56108) (xy 2.30632 3.63474) (xy 2.19202 3.70586) (xy 2.07391 3.77317)
				(xy 1.95453 3.83667) (xy 1.83261 3.89509) (xy 1.70942 3.95097) (xy 1.58496 4.00304) (xy 1.45796 4.0513)
				(xy 1.33096 4.09448) (xy 1.20142 4.13385) (xy 1.07061 4.17068) (xy 0.9398 4.20116) (xy 0.80645 4.2291)
				(xy 0.6731 4.25196) (xy 0.53975 4.27101) (xy 0.40513 4.28625) (xy 0.27051 4.29641) (xy 0.13462 4.30276)
			)
			(stroke
				(width 0)
				(type default)
			)
			(fill no)
			(layer "F.CrtYd")
		)
		(fp_poly
			(pts
				(xy 0 4.3053) (xy -0.13462 4.30276) (xy -0.27051 4.29641) (xy -0.40513 4.28625) (xy -0.53975 4.27101)
				(xy -0.6731 4.25196) (xy -0.80645 4.2291) (xy -0.9398 4.20116) (xy -1.07061 4.17068) (xy -1.20142 4.13385)
				(xy -1.33096 4.09448) (xy -1.45796 4.0513) (xy -1.58496 4.00304) (xy -1.70942 3.95097) (xy -1.83261 3.89509)
				(xy -1.95453 3.83667) (xy -2.07391 3.77317) (xy -2.19202 3.70586) (xy -2.30632 3.63474) (xy -2.41935 3.56108)
				(xy -2.53111 3.48361) (xy -2.63906 3.40233) (xy -2.74447 3.31724) (xy -2.84734 3.22961) (xy -2.94767 3.13817)
				(xy -3.04419 3.04419) (xy -3.13817 2.94767) (xy -3.22961 2.84734) (xy -3.31724 2.74447) (xy -3.40233 2.63906)
				(xy -3.48361 2.53111) (xy -3.56108 2.41935) (xy -3.63474 2.30632) (xy -3.70586 2.19202) (xy -3.77317 2.07391)
				(xy -3.83667 1.95453) (xy -3.89509 1.83261) (xy -3.95097 1.70942) (xy -4.00304 1.58496) (xy -4.0513 1.45796)
				(xy -4.09448 1.33096) (xy -4.13385 1.20142) (xy -4.17068 1.07061) (xy -4.20116 0.9398) (xy -4.2291 0.80645)
				(xy -4.25196 0.6731) (xy -4.27101 0.53975) (xy -4.28625 0.40513) (xy -4.29641 0.27051) (xy -4.30276 0.13462)
				(xy -4.3053 0) (xy -4.30276 -0.13462) (xy -4.29641 -0.27051) (xy -4.28625 -0.40513) (xy -4.27101 -0.53975)
				(xy -4.25196 -0.6731) (xy -4.2291 -0.80645) (xy -4.20116 -0.9398) (xy -4.17068 -1.07061) (xy -4.13385 -1.20142)
				(xy -4.09448 -1.33096) (xy -4.0513 -1.45796) (xy -4.00304 -1.58496) (xy -3.95097 -1.70942) (xy -3.89509 -1.83261)
				(xy -3.83667 -1.95453) (xy -3.77317 -2.07391) (xy -3.70586 -2.19202) (xy -3.63474 -2.30632) (xy -3.56108 -2.41935)
				(xy -3.48361 -2.53111) (xy -3.40233 -2.63906) (xy -3.31724 -2.74447) (xy -3.22961 -2.84734) (xy -3.13817 -2.94767)
				(xy -3.04419 -3.04419) (xy -2.94767 -3.13817) (xy -2.84734 -3.22961) (xy -2.74447 -3.31724) (xy -2.63906 -3.40233)
				(xy -2.53111 -3.48361) (xy -2.41935 -3.56108) (xy -2.30632 -3.63474) (xy -2.19202 -3.70586) (xy -2.07391 -3.77317)
				(xy -1.95453 -3.83667) (xy -1.83261 -3.89509) (xy -1.70942 -3.95097) (xy -1.58496 -4.00304) (xy -1.45796 -4.0513)
				(xy -1.33096 -4.09448) (xy -1.20142 -4.13385) (xy -1.07061 -4.17068) (xy -0.9398 -4.20116) (xy -0.80645 -4.2291)
				(xy -0.6731 -4.25196) (xy -0.53975 -4.27101) (xy -0.40513 -4.28625) (xy -0.27051 -4.29641) (xy -0.13462 -4.30276)
				(xy 0 -4.3053) (xy 0.13462 -4.30276) (xy 0.27051 -4.29641) (xy 0.40513 -4.28625) (xy 0.53975 -4.27101)
				(xy 0.6731 -4.25196) (xy 0.80645 -4.2291) (xy 0.9398 -4.20116) (xy 1.07061 -4.17068) (xy 1.20142 -4.13385)
				(xy 1.33096 -4.09448) (xy 1.45796 -4.0513) (xy 1.58496 -4.00304) (xy 1.70942 -3.95097) (xy 1.83261 -3.89509)
				(xy 1.95453 -3.83667) (xy 2.07391 -3.77317) (xy 2.19202 -3.70586) (xy 2.30632 -3.63474) (xy 2.41935 -3.56108)
				(xy 2.53111 -3.48361) (xy 2.63906 -3.40233) (xy 2.74447 -3.31724) (xy 2.84734 -3.22961) (xy 2.94767 -3.13817)
				(xy 3.04419 -3.04419) (xy 3.13817 -2.94767) (xy 3.22961 -2.84734) (xy 3.31724 -2.74447) (xy 3.40233 -2.63906)
				(xy 3.48361 -2.53111) (xy 3.56108 -2.41935) (xy 3.63474 -2.30632) (xy 3.70586 -2.19202) (xy 3.77317 -2.07391)
				(xy 3.83667 -1.95453) (xy 3.89509 -1.83261) (xy 3.95097 -1.70942) (xy 4.00304 -1.58496) (xy 4.0513 -1.45796)
				(xy 4.09448 -1.33096) (xy 4.13385 -1.20142) (xy 4.17068 -1.07061) (xy 4.20116 -0.9398) (xy 4.2291 -0.80645)
				(xy 4.25196 -0.6731) (xy 4.27101 -0.53975) (xy 4.28625 -0.40513) (xy 4.29641 -0.27051) (xy 4.30276 -0.13462)
				(xy 4.3053 0) (xy 4.30276 0.13462) (xy 4.29641 0.27051) (xy 4.28625 0.40513) (xy 4.27101 0.53975)
				(xy 4.25196 0.6731) (xy 4.2291 0.80645) (xy 4.20116 0.9398) (xy 4.17068 1.07061) (xy 4.13385 1.20142)
				(xy 4.09448 1.33096) (xy 4.0513 1.45796) (xy 4.00304 1.58496) (xy 3.95097 1.70942) (xy 3.89509 1.83261)
				(xy 3.83667 1.95453) (xy 3.77317 2.07391) (xy 3.70586 2.19202) (xy 3.63474 2.30632) (xy 3.56108 2.41935)
				(xy 3.48361 2.53111) (xy 3.40233 2.63906) (xy 3.31724 2.74447) (xy 3.22961 2.84734) (xy 3.13817 2.94767)
				(xy 3.04419 3.04419) (xy 2.94767 3.13817) (xy 2.84734 3.22961) (xy 2.74447 3.31724) (xy 2.63906 3.40233)
				(xy 2.53111 3.48361) (xy 2.41935 3.56108) (xy 2.30632 3.63474) (xy 2.19202 3.70586) (xy 2.07391 3.77317)
				(xy 1.95453 3.83667) (xy 1.83261 3.89509) (xy 1.70942 3.95097) (xy 1.58496 4.00304) (xy 1.45796 4.0513)
				(xy 1.33096 4.09448) (xy 1.20142 4.13385) (xy 1.07061 4.17068) (xy 0.9398 4.20116) (xy 0.80645 4.2291)
				(xy 0.6731 4.25196) (xy 0.53975 4.27101) (xy 0.40513 4.28625) (xy 0.27051 4.29641) (xy 0.13462 4.30276)
			)
			(stroke
				(width 0)
				(type default)
			)
			(fill no)
			(layer "F.Fab")
		)
		(pad "1" thru_hole circle
			(at 0 0)
			(size 8.001 8.001)
			(drill 3.5052)
			(layers "*.Cu" "*.Mask")
			(remove_unused_layers no)
			(net "GND")
			(clearance -1.7399)
			(thermal_gap 0.3048)
			(padstack
				(mode front_inner_back)
				(layer "Inner"
					(shape circle)
					(size 3.9116 3.9116)
					(clearance 0.3048)
				)
				(layer "B.Cu"
					(shape circle)
					(size 8.001 8.001)
					(clearance -1.7399)
				)
			)
		)
	)
	(footprint ""
		(layer "F.Cu")
		(at 20.385024 -175.37811 90)
		(property "Reference" "R23"
			(at 0 0 90)
			(layer "F.SilkS")
			(hide yes)
			(effects
				(font
					(size 1.27 1.27)
				)
			)
		)
		(property "Value" "4K7R2F-GP"
			(at 0.064008 -3.993896 90)
			(unlocked yes)
			(layer "F.Fab")
			(hide yes)
			(effects
				(font
					(size 1.016 1.016)
					(thickness 0.1524)
				)
			)
		)
		(property "Device Type" "R402H16"
			(at 0.064008 -5.517896 90)
			(unlocked yes)
			(layer "F.Fab")
			(hide yes)
			(effects
				(font
					(size 1.016 1.016)
					(thickness 0.1524)
				)
			)
		)
		(duplicate_pad_numbers_are_jumpers no)
		(fp_line
			(start 0.508 -0.9398)
			(end -0.508 -0.9398)
			(stroke
				(width 0.1524)
				(type default)
			)
			(layer "F.SilkS")
		)
		(fp_line
			(start -0.508 -0.9398)
			(end -0.508 0.9398)
			(stroke
				(width 0.1524)
				(type default)
			)
			(layer "F.SilkS")
		)
		(fp_rect
			(start -0.508 0.9398)
			(end 0.508 -0.9398)
			(stroke
				(width 0)
				(type default)
			)
			(fill no)
			(layer "F.CrtYd")
		)
		(fp_rect
			(start -0.508 0.9398)
			(end 0.508 -0.9398)
			(stroke
				(width 0)
				(type default)
			)
			(fill no)
			(layer "F.Fab")
		)
		(pad "1" smd custom
			(at 0 -0.4445 90)
			(size 0.1397 0.1397)
			(layers "F.Cu" "F.Mask" "F.Paste")
			(net "P3V3")
			(options
				(clearance outline)
				(anchor circle)
			)
			(primitives
				(gr_poly
					(pts
						(arc
							(start -0.1778 -0.2794)
							(mid -0.249642 -0.249642)
							(end -0.2794 -0.1778)
						)
						(arc
							(start -0.2794 0.1778)
							(mid -0.249642 0.249642)
							(end -0.1778 0.2794)
						)
						(arc
							(start 0.1778 0.2794)
							(mid 0.249642 0.249642)
							(end 0.2794 0.1778)
						)
						(arc
							(start 0.2794 -0.1778)
							(mid 0.249642 -0.249642)
							(end 0.1778 -0.2794)
						)
					)
					(width 0)
					(fill yes)
				)
			)
		)
		(pad "2" smd custom
			(at 0 0.4445 90)
			(size 0.1397 0.1397)
			(layers "F.Cu" "F.Mask" "F.Paste")
			(net "NCT7368S_SEL")
			(options
				(clearance outline)
				(anchor circle)
			)
			(primitives
				(gr_poly
					(pts
						(arc
							(start -0.1778 -0.2794)
							(mid -0.249642 -0.249642)
							(end -0.2794 -0.1778)
						)
						(arc
							(start -0.2794 0.1778)
							(mid -0.249642 0.249642)
							(end -0.1778 0.2794)
						)
						(arc
							(start 0.1778 0.2794)
							(mid 0.249642 0.249642)
							(end 0.2794 0.1778)
						)
						(arc
							(start 0.2794 -0.1778)
							(mid 0.249642 -0.249642)
							(end 0.1778 -0.2794)
						)
					)
					(width 0)
					(fill yes)
				)
			)
		)
	)
	(footprint ""
		(layer "F.Cu")
		(at 15.9258 -145.542 -90)
		(property "Reference" "C30"
			(at 0 0 270)
			(layer "F.SilkS")
			(hide yes)
			(effects
				(font
					(size 1.27 1.27)
				)
			)
		)
		(property "Value" "SCD1U16V2KX-3GP"
			(at 1.1811 -2.7051 270)
			(unlocked yes)
			(layer "F.Fab")
			(hide yes)
			(effects
				(font
					(size 1.016 1.016)
					(thickness 0.1524)
				)
			)
		)
		(property "Device Type" "C402H22"
			(at 1.1811 -4.2291 270)
			(unlocked yes)
			(layer "F.Fab")
			(hide yes)
			(effects
				(font
					(size 1.016 1.016)
					(thickness 0.1524)
				)
			)
		)
		(duplicate_pad_numbers_are_jumpers no)
		(fp_rect
			(start -0.4318 0.9525)
			(end 0.4318 -0.9525)
			(stroke
				(width 0)
				(type default)
			)
			(fill no)
			(layer "F.CrtYd")
		)
		(fp_rect
			(start -0.4318 0.9525)
			(end 0.4318 -0.9525)
			(stroke
				(width 0)
				(type default)
			)
			(fill no)
			(layer "F.Fab")
		)
		(pad "1" smd custom
			(at 0 -0.4445 270)
			(size 0.1524 0.1524)
			(layers "F.Cu" "F.Mask" "F.Paste")
			(net "FAN_TACH9")
			(options
				(clearance outline)
				(anchor circle)
			)
			(primitives
				(gr_poly
					(pts
						(arc
							(start 0.3048 -0.2032)
							(mid 0.275042 -0.275042)
							(end 0.2032 -0.3048)
						)
						(arc
							(start -0.2032 -0.3048)
							(mid -0.275042 -0.275042)
							(end -0.3048 -0.2032)
						)
						(arc
							(start -0.3048 0.2032)
							(mid -0.275042 0.275042)
							(end -0.2032 0.3048)
						)
						(arc
							(start 0.2032 0.3048)
							(mid 0.275042 0.275042)
							(end 0.3048 0.2032)
						)
					)
					(width 0)
					(fill yes)
				)
			)
		)
		(pad "2" smd custom
			(at 0 0.4445 270)
			(size 0.1524 0.1524)
			(layers "F.Cu" "F.Mask" "F.Paste")
			(net "GND")
			(options
				(clearance outline)
				(anchor circle)
			)
			(primitives
				(gr_poly
					(pts
						(arc
							(start 0.3048 -0.2032)
							(mid 0.275042 -0.275042)
							(end 0.2032 -0.3048)
						)
						(arc
							(start -0.2032 -0.3048)
							(mid -0.275042 -0.275042)
							(end -0.3048 -0.2032)
						)
						(arc
							(start -0.3048 0.2032)
							(mid -0.275042 0.275042)
							(end -0.2032 0.3048)
						)
						(arc
							(start 0.2032 0.3048)
							(mid 0.275042 0.275042)
							(end 0.3048 0.2032)
						)
					)
					(width 0)
					(fill yes)
				)
			)
		)
	)
	(footprint ""
		(layer "F.Cu")
		(at 21.7678 -218.821 90)
		(property "Reference" "R134"
			(at 0 0 90)
			(layer "F.SilkS")
			(hide yes)
			(effects
				(font
					(size 1.27 1.27)
				)
			)
		)
		(property "Value" "4K7R2F-GP"
			(at 0.064008 -3.993896 90)
			(unlocked yes)
			(layer "F.Fab")
			(hide yes)
			(effects
				(font
					(size 1.016 1.016)
					(thickness 0.1524)
				)
			)
		)
		(property "Device Type" "R402H16"
			(at 0.064008 -5.517896 90)
			(unlocked yes)
			(layer "F.Fab")
			(hide yes)
			(effects
				(font
					(size 1.016 1.016)
					(thickness 0.1524)
				)
			)
		)
		(duplicate_pad_numbers_are_jumpers no)
		(fp_line
			(start 0.508 -0.9398)
			(end -0.508 -0.9398)
			(stroke
				(width 0.1524)
				(type default)
			)
			(layer "F.SilkS")
		)
		(fp_line
			(start -0.508 -0.9398)
			(end -0.508 0.9398)
			(stroke
				(width 0.1524)
				(type default)
			)
			(layer "F.SilkS")
		)
		(fp_rect
			(start -0.508 0.9398)
			(end 0.508 -0.9398)
			(stroke
				(width 0)
				(type default)
			)
			(fill no)
			(layer "F.CrtYd")
		)
		(fp_rect
			(start -0.508 0.9398)
			(end 0.508 -0.9398)
			(stroke
				(width 0)
				(type default)
			)
			(fill no)
			(layer "F.Fab")
		)
		(pad "1" smd custom
			(at 0 -0.4445 90)
			(size 0.1397 0.1397)
			(layers "F.Cu" "F.Mask" "F.Paste")
			(net "P3V3")
			(options
				(clearance outline)
				(anchor circle)
			)
			(primitives
				(gr_poly
					(pts
						(arc
							(start -0.1778 -0.2794)
							(mid -0.249642 -0.249642)
							(end -0.2794 -0.1778)
						)
						(arc
							(start -0.2794 0.1778)
							(mid -0.249642 0.249642)
							(end -0.1778 0.2794)
						)
						(arc
							(start 0.1778 0.2794)
							(mid 0.249642 0.249642)
							(end 0.2794 0.1778)
						)
						(arc
							(start 0.2794 -0.1778)
							(mid 0.249642 -0.249642)
							(end 0.1778 -0.2794)
						)
					)
					(width 0)
					(fill yes)
				)
			)
		)
		(pad "2" smd custom
			(at 0 0.4445 90)
			(size 0.1397 0.1397)
			(layers "F.Cu" "F.Mask" "F.Paste")
			(net "PWM_OUT_FAN2")
			(options
				(clearance outline)
				(anchor circle)
			)
			(primitives
				(gr_poly
					(pts
						(arc
							(start -0.1778 -0.2794)
							(mid -0.249642 -0.249642)
							(end -0.2794 -0.1778)
						)
						(arc
							(start -0.2794 0.1778)
							(mid -0.249642 0.249642)
							(end -0.1778 0.2794)
						)
						(arc
							(start 0.1778 0.2794)
							(mid 0.249642 0.249642)
							(end 0.2794 0.1778)
						)
						(arc
							(start 0.2794 -0.1778)
							(mid 0.249642 -0.249642)
							(end 0.1778 -0.2794)
						)
					)
					(width 0)
					(fill yes)
				)
			)
		)
	)
)
